(kicad_pcb
	(version 20260206)
	(generator "pcbnew")
	(generator_version "10.0")
	(general
		(thickness 1.6)
		(legacy_teardrops no)
	)
	(paper "A4")
	(title_block
		(title "peb — Lightning_PEB_BRD.brd")
		(comment 1 "Lightning (Wiwynn / Facebook NVMe JBOF) / footprints 1404-1410 of 2563")
	)
	(layers
		(0 "F.Cu" signal "TOP")
		(4 "In1.Cu" signal "L2GND")
		(6 "In2.Cu" signal "L3")
		(8 "In3.Cu" signal "L4VCC")
		(10 "In4.Cu" signal "L5VCC")
		(12 "In5.Cu" signal "L6")
		(14 "In6.Cu" signal "L7GND")
		(2 "B.Cu" signal "BOTTOM")
		(9 "F.Adhes" user "F.Adhesive")
		(11 "B.Adhes" user "B.Adhesive")
		(13 "F.Paste" user "Package Geometry/Pastemask Top")
		(15 "B.Paste" user "Package Geometry/Pastemask Bottom")
		(5 "F.SilkS" user "Ref Des/Silkscreen Top")
		(7 "B.SilkS" user "Ref Des/Silkscreen Bottom")
		(1 "F.Mask" user "Board Geometry/Soldermask Top")
		(3 "B.Mask" user "Board Geometry/Soldermask Bottom")
		(17 "Dwgs.User" user "User.Drawings")
		(19 "Cmts.User" user "User.Comments")
		(21 "Eco1.User" user "User.Eco1")
		(23 "Eco2.User" user "User.Eco2")
		(25 "Edge.Cuts" user "Board Geometry/Outline")
		(27 "Margin" user)
		(31 "F.CrtYd" user "Package Geometry/Place Bound Top")
		(29 "B.CrtYd" user "Package Geometry/Place Bound Bottom")
		(35 "F.Fab" user "Ref Des/Assembly Top")
		(33 "B.Fab" user "Ref Des/Assembly Bottom")
	)
	(footprint ""
		(layer "F.Cu")
		(at 164.084 -33.528)
		(property "Reference" "C397"
			(at 0 0 0)
			(layer "F.SilkS")
			(hide yes)
			(effects
				(font
					(size 1.27 1.27)
				)
			)
		)
		(property "Value" "SCD22U10V2KX-1GP"
			(at 1.1811 -2.7051 0)
			(unlocked yes)
			(layer "F.Fab")
			(hide yes)
			(effects
				(font
					(size 1.016 1.016)
					(thickness 0.1524)
				)
			)
		)
		(property "Device Type" "C402H22"
			(at 1.1811 -4.2291 0)
			(unlocked yes)
			(layer "F.Fab")
			(hide yes)
			(effects
				(font
					(size 1.016 1.016)
					(thickness 0.1524)
				)
			)
		)
		(duplicate_pad_numbers_are_jumpers no)
		(fp_rect
			(start -0.4318 0.9525)
			(end 0.4318 -0.9525)
			(stroke
				(width 0)
				(type default)
			)
			(fill no)
			(layer "F.CrtYd")
		)
		(fp_rect
			(start -0.4318 0.9525)
			(end 0.4318 -0.9525)
			(stroke
				(width 0)
				(type default)
			)
			(fill no)
			(layer "F.Fab")
		)
		(pad "1" smd custom
			(at 0 -0.4445)
			(size 0.1524 0.1524)
			(layers "F.Cu" "F.Mask" "F.Paste")
			(net "PCIE_TX_CAP_N88")
			(options
				(clearance outline)
				(anchor circle)
			)
			(primitives
				(gr_poly
					(pts
						(arc
							(start 0.3048 -0.2032)
							(mid 0.275042 -0.275042)
							(end 0.2032 -0.3048)
						)
						(arc
							(start -0.2032 -0.3048)
							(mid -0.275042 -0.275042)
							(end -0.3048 -0.2032)
						)
						(arc
							(start -0.3048 0.2032)
							(mid -0.275042 0.275042)
							(end -0.2032 0.3048)
						)
						(arc
							(start 0.2032 0.3048)
							(mid 0.275042 0.275042)
							(end 0.3048 0.2032)
						)
					)
					(width 0)
					(fill yes)
				)
			)
		)
		(pad "2" smd custom
			(at 0 0.4445)
			(size 0.1524 0.1524)
			(layers "F.Cu" "F.Mask" "F.Paste")
			(net "PCIE_TX_N88")
			(options
				(clearance outline)
				(anchor circle)
			)
			(primitives
				(gr_poly
					(pts
						(arc
							(start 0.3048 -0.2032)
							(mid 0.275042 -0.275042)
							(end 0.2032 -0.3048)
						)
						(arc
							(start -0.2032 -0.3048)
							(mid -0.275042 -0.275042)
							(end -0.3048 -0.2032)
						)
						(arc
							(start -0.3048 0.2032)
							(mid -0.275042 0.275042)
							(end -0.2032 0.3048)
						)
						(arc
							(start 0.2032 0.3048)
							(mid 0.275042 0.275042)
							(end 0.3048 0.2032)
						)
					)
					(width 0)
					(fill yes)
				)
			)
		)
	)
	(footprint ""
		(layer "F.Cu")
		(at 56.134 -133.985 180)
		(property "Reference" "C8085"
			(at 0 0 180)
			(layer "F.SilkS")
			(hide yes)
			(effects
				(font
					(size 1.27 1.27)
				)
			)
		)
		(property "Value" "SCD1U25V2KX-2-GP"
			(at 1.1811 -2.7051 180)
			(unlocked yes)
			(layer "F.Fab")
			(hide yes)
			(effects
				(font
					(size 1.016 1.016)
					(thickness 0.1524)
				)
			)
		)
		(property "Device Type" "C402H22"
			(at 1.1811 -4.2291 180)
			(unlocked yes)
			(layer "F.Fab")
			(hide yes)
			(effects
				(font
					(size 1.016 1.016)
					(thickness 0.1524)
				)
			)
		)
		(duplicate_pad_numbers_are_jumpers no)
		(fp_rect
			(start -0.4318 0.9525)
			(end 0.4318 -0.9525)
			(stroke
				(width 0)
				(type default)
			)
			(fill no)
			(layer "F.CrtYd")
		)
		(fp_rect
			(start -0.4318 0.9525)
			(end 0.4318 -0.9525)
			(stroke
				(width 0)
				(type default)
			)
			(fill no)
			(layer "F.Fab")
		)
		(pad "1" smd custom
			(at 0 -0.4445 180)
			(size 0.1524 0.1524)
			(layers "F.Cu" "F.Mask" "F.Paste")
			(net "ADC_P1V8_STBY")
			(options
				(clearance outline)
				(anchor circle)
			)
			(primitives
				(gr_poly
					(pts
						(arc
							(start 0.3048 -0.2032)
							(mid 0.275042 -0.275042)
							(end 0.2032 -0.3048)
						)
						(arc
							(start -0.2032 -0.3048)
							(mid -0.275042 -0.275042)
							(end -0.3048 -0.2032)
						)
						(arc
							(start -0.3048 0.2032)
							(mid -0.275042 0.275042)
							(end -0.2032 0.3048)
						)
						(arc
							(start 0.2032 0.3048)
							(mid 0.275042 0.275042)
							(end 0.3048 0.2032)
						)
					)
					(width 0)
					(fill yes)
				)
			)
		)
		(pad "2" smd custom
			(at 0 0.4445 180)
			(size 0.1524 0.1524)
			(layers "F.Cu" "F.Mask" "F.Paste")
			(net "GND")
			(options
				(clearance outline)
				(anchor circle)
			)
			(primitives
				(gr_poly
					(pts
						(arc
							(start 0.3048 -0.2032)
							(mid 0.275042 -0.275042)
							(end 0.2032 -0.3048)
						)
						(arc
							(start -0.2032 -0.3048)
							(mid -0.275042 -0.275042)
							(end -0.3048 -0.2032)
						)
						(arc
							(start -0.3048 0.2032)
							(mid -0.275042 0.275042)
							(end -0.2032 0.3048)
						)
						(arc
							(start 0.2032 0.3048)
							(mid 0.275042 0.275042)
							(end 0.3048 0.2032)
						)
					)
					(width 0)
					(fill yes)
				)
			)
		)
	)
	(footprint ""
		(layer "F.Cu")
		(at 20.447 -143.383)
		(property "Reference" "C202"
			(at 0 0 0)
			(layer "F.SilkS")
			(hide yes)
			(effects
				(font
					(size 1.27 1.27)
				)
			)
		)
		(property "Value" "SCD1U16V2KX-3GP"
			(at 1.1811 -2.7051 0)
			(unlocked yes)
			(layer "F.Fab")
			(hide yes)
			(effects
				(font
					(size 1.016 1.016)
					(thickness 0.1524)
				)
			)
		)
		(property "Device Type" "C402H22"
			(at 1.1811 -4.2291 0)
			(unlocked yes)
			(layer "F.Fab")
			(hide yes)
			(effects
				(font
					(size 1.016 1.016)
					(thickness 0.1524)
				)
			)
		)
		(duplicate_pad_numbers_are_jumpers no)
		(fp_rect
			(start -0.4318 0.9525)
			(end 0.4318 -0.9525)
			(stroke
				(width 0)
				(type default)
			)
			(fill no)
			(layer "F.CrtYd")
		)
		(fp_rect
			(start -0.4318 0.9525)
			(end 0.4318 -0.9525)
			(stroke
				(width 0)
				(type default)
			)
			(fill no)
			(layer "F.Fab")
		)
		(pad "1" smd custom
			(at 0 -0.4445)
			(size 0.1524 0.1524)
			(layers "F.Cu" "F.Mask" "F.Paste")
			(net "V1PLLAV12")
			(options
				(clearance outline)
				(anchor circle)
			)
			(primitives
				(gr_poly
					(pts
						(arc
							(start 0.3048 -0.2032)
							(mid 0.275042 -0.275042)
							(end 0.2032 -0.3048)
						)
						(arc
							(start -0.2032 -0.3048)
							(mid -0.275042 -0.275042)
							(end -0.3048 -0.2032)
						)
						(arc
							(start -0.3048 0.2032)
							(mid -0.275042 0.275042)
							(end -0.2032 0.3048)
						)
						(arc
							(start 0.2032 0.3048)
							(mid 0.275042 0.275042)
							(end 0.3048 0.2032)
						)
					)
					(width 0)
					(fill yes)
				)
			)
		)
		(pad "2" smd custom
			(at 0 0.4445)
			(size 0.1524 0.1524)
			(layers "F.Cu" "F.Mask" "F.Paste")
			(net "GND")
			(options
				(clearance outline)
				(anchor circle)
			)
			(primitives
				(gr_poly
					(pts
						(arc
							(start 0.3048 -0.2032)
							(mid 0.275042 -0.275042)
							(end 0.2032 -0.3048)
						)
						(arc
							(start -0.2032 -0.3048)
							(mid -0.275042 -0.275042)
							(end -0.3048 -0.2032)
						)
						(arc
							(start -0.3048 0.2032)
							(mid -0.275042 0.275042)
							(end -0.2032 0.3048)
						)
						(arc
							(start 0.2032 0.3048)
							(mid 0.275042 0.275042)
							(end 0.3048 0.2032)
						)
					)
					(width 0)
					(fill yes)
				)
			)
		)
	)
	(footprint ""
		(layer "F.Cu")
		(at 50.292 -199.39 90)
		(property "Reference" "R886"
			(at 0 0 90)
			(layer "F.SilkS")
			(hide yes)
			(effects
				(font
					(size 1.27 1.27)
				)
			)
		)
		(property "Value" "4K7R2J-2-GP"
			(at 0.064008 -3.993896 90)
			(unlocked yes)
			(layer "F.Fab")
			(hide yes)
			(effects
				(font
					(size 1.016 1.016)
					(thickness 0.1524)
				)
			)
		)
		(property "Device Type" "R402H16"
			(at 0.064008 -5.517896 90)
			(unlocked yes)
			(layer "F.Fab")
			(hide yes)
			(effects
				(font
					(size 1.016 1.016)
					(thickness 0.1524)
				)
			)
		)
		(duplicate_pad_numbers_are_jumpers no)
		(fp_line
			(start 0.508 -0.9398)
			(end -0.508 -0.9398)
			(stroke
				(width 0.1524)
				(type default)
			)
			(layer "F.SilkS")
		)
		(fp_line
			(start -0.508 -0.9398)
			(end -0.508 0.9398)
			(stroke
				(width 0.1524)
				(type default)
			)
			(layer "F.SilkS")
		)
		(fp_rect
			(start -0.508 0.9398)
			(end 0.508 -0.9398)
			(stroke
				(width 0)
				(type default)
			)
			(fill no)
			(layer "F.CrtYd")
		)
		(fp_rect
			(start -0.508 0.9398)
			(end 0.508 -0.9398)
			(stroke
				(width 0)
				(type default)
			)
			(fill no)
			(layer "F.Fab")
		)
		(pad "1" smd custom
			(at 0 -0.4445 90)
			(size 0.1397 0.1397)
			(layers "F.Cu" "F.Mask" "F.Paste")
			(net "P3V3_STBY")
			(options
				(clearance outline)
				(anchor circle)
			)
			(primitives
				(gr_poly
					(pts
						(arc
							(start -0.1778 -0.2794)
							(mid -0.249642 -0.249642)
							(end -0.2794 -0.1778)
						)
						(arc
							(start -0.2794 0.1778)
							(mid -0.249642 0.249642)
							(end -0.1778 0.2794)
						)
						(arc
							(start 0.1778 0.2794)
							(mid 0.249642 0.249642)
							(end 0.2794 0.1778)
						)
						(arc
							(start 0.2794 -0.1778)
							(mid 0.249642 -0.249642)
							(end 0.1778 -0.2794)
						)
					)
					(width 0)
					(fill yes)
				)
			)
		)
		(pad "2" smd custom
			(at 0 0.4445 90)
			(size 0.1397 0.1397)
			(layers "F.Cu" "F.Mask" "F.Paste")
			(net "BUF_I2C7_B_DPB_SDA_R")
			(options
				(clearance outline)
				(anchor circle)
			)
			(primitives
				(gr_poly
					(pts
						(arc
							(start -0.1778 -0.2794)
							(mid -0.249642 -0.249642)
							(end -0.2794 -0.1778)
						)
						(arc
							(start -0.2794 0.1778)
							(mid -0.249642 0.249642)
							(end -0.1778 0.2794)
						)
						(arc
							(start 0.1778 0.2794)
							(mid 0.249642 0.249642)
							(end 0.2794 0.1778)
						)
						(arc
							(start 0.2794 -0.1778)
							(mid 0.249642 -0.249642)
							(end 0.1778 -0.2794)
						)
					)
					(width 0)
					(fill yes)
				)
			)
		)
	)
	(footprint ""
		(layer "F.Cu")
		(at 181.61 -21.59 -90)
		(property "Reference" "C405"
			(at 0 0 270)
			(layer "F.SilkS")
			(hide yes)
			(effects
				(font
					(size 1.27 1.27)
				)
			)
		)
		(property "Value" "SCD22U10V2KX-1GP"
			(at 1.1811 -2.7051 270)
			(unlocked yes)
			(layer "F.Fab")
			(hide yes)
			(effects
				(font
					(size 1.016 1.016)
					(thickness 0.1524)
				)
			)
		)
		(property "Device Type" "C402H22"
			(at 1.1811 -4.2291 270)
			(unlocked yes)
			(layer "F.Fab")
			(hide yes)
			(effects
				(font
					(size 1.016 1.016)
					(thickness 0.1524)
				)
			)
		)
		(duplicate_pad_numbers_are_jumpers no)
		(fp_rect
			(start -0.4318 0.9525)
			(end 0.4318 -0.9525)
			(stroke
				(width 0)
				(type default)
			)
			(fill no)
			(layer "F.CrtYd")
		)
		(fp_rect
			(start -0.4318 0.9525)
			(end 0.4318 -0.9525)
			(stroke
				(width 0)
				(type default)
			)
			(fill no)
			(layer "F.Fab")
		)
		(pad "1" smd custom
			(at 0 -0.4445 270)
			(size 0.1524 0.1524)
			(layers "F.Cu" "F.Mask" "F.Paste")
			(net "PCIE_TX_CAP_N92")
			(options
				(clearance outline)
				(anchor circle)
			)
			(primitives
				(gr_poly
					(pts
						(arc
							(start 0.3048 -0.2032)
							(mid 0.275042 -0.275042)
							(end 0.2032 -0.3048)
						)
						(arc
							(start -0.2032 -0.3048)
							(mid -0.275042 -0.275042)
							(end -0.3048 -0.2032)
						)
						(arc
							(start -0.3048 0.2032)
							(mid -0.275042 0.275042)
							(end -0.2032 0.3048)
						)
						(arc
							(start 0.2032 0.3048)
							(mid 0.275042 0.275042)
							(end 0.3048 0.2032)
						)
					)
					(width 0)
					(fill yes)
				)
			)
		)
		(pad "2" smd custom
			(at 0 0.4445 270)
			(size 0.1524 0.1524)
			(layers "F.Cu" "F.Mask" "F.Paste")
			(net "PCIE_TX_N92")
			(options
				(clearance outline)
				(anchor circle)
			)
			(primitives
				(gr_poly
					(pts
						(arc
							(start 0.3048 -0.2032)
							(mid 0.275042 -0.275042)
							(end 0.2032 -0.3048)
						)
						(arc
							(start -0.2032 -0.3048)
							(mid -0.275042 -0.275042)
							(end -0.3048 -0.2032)
						)
						(arc
							(start -0.3048 0.2032)
							(mid -0.275042 0.275042)
							(end -0.2032 0.3048)
						)
						(arc
							(start 0.2032 0.3048)
							(mid 0.275042 0.275042)
							(end 0.3048 0.2032)
						)
					)
					(width 0)
					(fill yes)
				)
			)
		)
	)
	(footprint ""
		(layer "F.Cu")
		(at 270.302482 -12.403328 90)
		(property "Reference" "R219"
			(at 0 0 90)
			(layer "F.SilkS")
			(hide yes)
			(effects
				(font
					(size 1.27 1.27)
				)
			)
		)
		(property "Value" "4K7R2F-GP"
			(at 0.064008 -3.993896 90)
			(unlocked yes)
			(layer "F.Fab")
			(hide yes)
			(effects
				(font
					(size 1.016 1.016)
					(thickness 0.1524)
				)
			)
		)
		(property "Device Type" "R402H16"
			(at 0.064008 -5.517896 90)
			(unlocked yes)
			(layer "F.Fab")
			(hide yes)
			(effects
				(font
					(size 1.016 1.016)
					(thickness 0.1524)
				)
			)
		)
		(duplicate_pad_numbers_are_jumpers no)
		(fp_line
			(start 0.508 -0.9398)
			(end -0.508 -0.9398)
			(stroke
				(width 0.1524)
				(type default)
			)
			(layer "F.SilkS")
		)
		(fp_line
			(start -0.508 -0.9398)
			(end -0.508 0.9398)
			(stroke
				(width 0.1524)
				(type default)
			)
			(layer "F.SilkS")
		)
		(fp_rect
			(start -0.508 0.9398)
			(end 0.508 -0.9398)
			(stroke
				(width 0)
				(type default)
			)
			(fill no)
			(layer "F.CrtYd")
		)
		(fp_rect
			(start -0.508 0.9398)
			(end 0.508 -0.9398)
			(stroke
				(width 0)
				(type default)
			)
			(fill no)
			(layer "F.Fab")
		)
		(pad "1" smd custom
			(at 0 -0.4445 90)
			(size 0.1397 0.1397)
			(layers "F.Cu" "F.Mask" "F.Paste")
			(net "P3V3_STBY")
			(options
				(clearance outline)
				(anchor circle)
			)
			(primitives
				(gr_poly
					(pts
						(arc
							(start -0.1778 -0.2794)
							(mid -0.249642 -0.249642)
							(end -0.2794 -0.1778)
						)
						(arc
							(start -0.2794 0.1778)
							(mid -0.249642 0.249642)
							(end -0.1778 0.2794)
						)
						(arc
							(start 0.1778 0.2794)
							(mid 0.249642 0.249642)
							(end 0.2794 0.1778)
						)
						(arc
							(start 0.2794 -0.1778)
							(mid 0.249642 -0.249642)
							(end 0.1778 -0.2794)
						)
					)
					(width 0)
					(fill yes)
				)
			)
		)
		(pad "2" smd custom
			(at 0 0.4445 90)
			(size 0.1397 0.1397)
			(layers "F.Cu" "F.Mask" "F.Paste")
			(net "CLK_P_5_R")
			(options
				(clearance outline)
				(anchor circle)
			)
			(primitives
				(gr_poly
					(pts
						(arc
							(start -0.1778 -0.2794)
							(mid -0.249642 -0.249642)
							(end -0.2794 -0.1778)
						)
						(arc
							(start -0.2794 0.1778)
							(mid -0.249642 0.249642)
							(end -0.1778 0.2794)
						)
						(arc
							(start 0.1778 0.2794)
							(mid 0.249642 0.249642)
							(end 0.2794 0.1778)
						)
						(arc
							(start 0.2794 -0.1778)
							(mid 0.249642 -0.249642)
							(end 0.1778 -0.2794)
						)
					)
					(width 0)
					(fill yes)
				)
			)
		)
	)
	(footprint ""
		(layer "F.Cu")
		(at 50.673 -200.914 180)
		(property "Reference" "R890"
			(at 0 0 180)
			(layer "F.SilkS")
			(hide yes)
			(effects
				(font
					(size 1.27 1.27)
				)
			)
		)
		(property "Value" "0R2J-2-GP"
			(at 0.064008 -3.993896 180)
			(unlocked yes)
			(layer "F.Fab")
			(hide yes)
			(effects
				(font
					(size 1.016 1.016)
					(thickness 0.1524)
				)
			)
		)
		(property "Device Type" "R402H16"
			(at 0.064008 -5.517896 180)
			(unlocked yes)
			(layer "F.Fab")
			(hide yes)
			(effects
				(font
					(size 1.016 1.016)
					(thickness 0.1524)
				)
			)
		)
		(duplicate_pad_numbers_are_jumpers no)
		(fp_line
			(start 0.508 -0.9398)
			(end -0.508 -0.9398)
			(stroke
				(width 0.1524)
				(type default)
			)
			(layer "F.SilkS")
		)
		(fp_line
			(start -0.508 -0.9398)
			(end -0.508 0.9398)
			(stroke
				(width 0.1524)
				(type default)
			)
			(layer "F.SilkS")
		)
		(fp_rect
			(start -0.508 0.9398)
			(end 0.508 -0.9398)
			(stroke
				(width 0)
				(type default)
			)
			(fill no)
			(layer "F.CrtYd")
		)
		(fp_rect
			(start -0.508 0.9398)
			(end 0.508 -0.9398)
			(stroke
				(width 0)
				(type default)
			)
			(fill no)
			(layer "F.Fab")
		)
		(pad "1" smd custom
			(at 0 -0.4445 180)
			(size 0.1397 0.1397)
			(layers "F.Cu" "F.Mask" "F.Paste")
			(net "BUF_I2C7_B_DPB_SDA_R")
			(options
				(clearance outline)
				(anchor circle)
			)
			(primitives
				(gr_poly
					(pts
						(arc
							(start -0.1778 -0.2794)
							(mid -0.249642 -0.249642)
							(end -0.2794 -0.1778)
						)
						(arc
							(start -0.2794 0.1778)
							(mid -0.249642 0.249642)
							(end -0.1778 0.2794)
						)
						(arc
							(start 0.1778 0.2794)
							(mid 0.249642 0.249642)
							(end 0.2794 0.1778)
						)
						(arc
							(start 0.2794 -0.1778)
							(mid 0.249642 -0.249642)
							(end 0.1778 -0.2794)
						)
					)
					(width 0)
					(fill yes)
				)
			)
		)
		(pad "2" smd custom
			(at 0 0.4445 180)
			(size 0.1397 0.1397)
			(layers "F.Cu" "F.Mask" "F.Paste")
			(net "BUF_I2C7_B_DPB_SDA")
			(options
				(clearance outline)
				(anchor circle)
			)
			(primitives
				(gr_poly
					(pts
						(arc
							(start -0.1778 -0.2794)
							(mid -0.249642 -0.249642)
							(end -0.2794 -0.1778)
						)
						(arc
							(start -0.2794 0.1778)
							(mid -0.249642 0.249642)
							(end -0.1778 0.2794)
						)
						(arc
							(start 0.1778 0.2794)
							(mid 0.249642 0.249642)
							(end 0.2794 0.1778)
						)
						(arc
							(start 0.2794 -0.1778)
							(mid 0.249642 -0.249642)
							(end 0.1778 -0.2794)
						)
					)
					(width 0)
					(fill yes)
				)
			)
		)
	)
)
